# T6G (Grand Teton) — schematic netlist excerpt (pin names and nets, part order shuffled) for the footprints in the layout excerpt that follows; sources: Cadence DE-HDL packaged netlist, KiCad conversion of 04192023_DAF0TMB3IC0_F0TG_MB_C_brd_V02_OCP.brd

C6757  Q_CAP  0.1UF 25V 10% EMPTY  pkg 0402  page 360 : A = P1V8_RETIMER_CPU0_EN ; B = GND
R9030  Q_RES  0 5% EMPTY  pkg 0402LF  page 136 : A = OCP_SFF_AUX_PWR_EN_R3 ; B = FM_PLD_OCP_SFF_AUX_PWR_EN

(kicad_pcb
	(version 20260206)
	(generator "pcbnew")
	(generator_version "10.0")
	(general
		(thickness 1.6)
		(legacy_teardrops no)
	)
	(paper "A4")
	(title_block
		(title "04192023_DAF0TMB3IC0_F0TG_MB_C_brd_V02_OCP.brd")
		(comment 1 "Grand Teton / footprints 4582-4583 of 8354")
	)
	(layers
		(0 "F.Cu" signal "TOP")
		(4 "In1.Cu" signal "GND")
		(6 "In2.Cu" signal "IN1")
		(8 "In3.Cu" signal "GND1")
		(10 "In4.Cu" signal "IN2")
		(12 "In5.Cu" signal "GND2")
		(14 "In6.Cu" signal "IN3")
		(16 "In7.Cu" signal "GND3")
		(18 "In8.Cu" signal "VCC")
		(20 "In9.Cu" signal "VCC1")
		(22 "In10.Cu" signal "GND4")
		(24 "In11.Cu" signal "IN4")
		(26 "In12.Cu" signal "GND5")
		(28 "In13.Cu" signal "IN5")
		(30 "In14.Cu" signal "GND6")
		(32 "In15.Cu" signal "IN6")
		(34 "In16.Cu" signal "GND7")
		(2 "B.Cu" signal "BOTTOM")
		(9 "F.Adhes" user "F.Adhesive")
		(11 "B.Adhes" user "B.Adhesive")
		(13 "F.Paste" user "Package Geometry/Pastemask Top")
		(15 "B.Paste" user "Package Geometry/Pastemask Bottom")
		(5 "F.SilkS" user "Ref Des/Silkscreen Top")
		(7 "B.SilkS" user "Ref Des/Silkscreen Bottom")
		(1 "F.Mask" user "Board Geometry/Soldermask Top")
		(3 "B.Mask" user "Board Geometry/Soldermask Bottom")
		(17 "Dwgs.User" user "User.Drawings")
		(19 "Cmts.User" user "User.Comments")
		(21 "Eco1.User" user "User.Eco1")
		(23 "Eco2.User" user "User.Eco2")
		(25 "Edge.Cuts" user "Board Geometry/Outline")
		(27 "Margin" user)
		(31 "F.CrtYd" user "Package Geometry/Place Bound Top")
		(29 "B.CrtYd" user "Package Geometry/Place Bound Bottom")
		(35 "F.Fab" user "Ref Des/Assembly Top")
		(33 "B.Fab" user "Ref Des/Assembly Bottom")
	)
	(footprint ""
		(layer "F.Cu")
		(at 239.432592 -289.012122 180)
		(property "Reference" "C6757"
			(at 0 0 180)
			(layer "F.SilkS")
			(hide yes)
			(effects
				(font
					(size 1.27 1.27)
				)
			)
		)
		(property "Value" ""
			(at 0 0 180)
			(layer "F.Fab")
			(effects
				(font
					(size 1.27 1.27)
				)
			)
		)
		(duplicate_pad_numbers_are_jumpers no)
		(fp_line
			(start 0.7874 0.4064)
			(end -0.7874 0.4064)
			(stroke
				(width 0.1524)
				(type default)
			)
			(layer "F.SilkS")
		)
		(fp_line
			(start 0.7874 -0.4064)
			(end 0.7874 0.4064)
			(stroke
				(width 0.1524)
				(type default)
			)
			(layer "F.SilkS")
		)
		(fp_line
			(start -0.7874 0.4064)
			(end -0.7874 -0.4064)
			(stroke
				(width 0.1524)
				(type default)
			)
			(layer "F.SilkS")
		)
		(fp_line
			(start -0.7874 -0.4064)
			(end 0.7874 -0.4064)
			(stroke
				(width 0.1524)
				(type default)
			)
			(layer "F.SilkS")
		)
		(fp_line
			(start 0.67945 0.3048)
			(end 0.120396 0.3048)
			(stroke
				(width 0.1)
				(type default)
			)
			(layer "F.Fab")
		)
		(fp_line
			(start 0.67945 -0.3048)
			(end 0.67945 0.3048)
			(stroke
				(width 0.1)
				(type default)
			)
			(layer "F.Fab")
		)
		(fp_line
			(start 0.12065 -0.2794)
			(end 0.12065 -0.3048)
			(stroke
				(width 0.1)
				(type default)
			)
			(layer "F.Fab")
		)
		(fp_line
			(start 0.12065 -0.3048)
			(end 0.67945 -0.3048)
			(stroke
				(width 0.1)
				(type default)
			)
			(layer "F.Fab")
		)
		(fp_line
			(start 0.120396 0.3048)
			(end 0.120396 0.2794)
			(stroke
				(width 0.1)
				(type default)
			)
			(layer "F.Fab")
		)
		(fp_line
			(start 0.120396 0.2794)
			(end -0.12065 0.2794)
			(stroke
				(width 0.1)
				(type default)
			)
			(layer "F.Fab")
		)
		(fp_line
			(start -0.12065 0.3048)
			(end -0.67945 0.3048)
			(stroke
				(width 0.1)
				(type default)
			)
			(layer "F.Fab")
		)
		(fp_line
			(start -0.12065 0.2794)
			(end -0.12065 0.3048)
			(stroke
				(width 0.1)
				(type default)
			)
			(layer "F.Fab")
		)
		(fp_line
			(start -0.12065 -0.2794)
			(end 0.12065 -0.2794)
			(stroke
				(width 0.1)
				(type default)
			)
			(layer "F.Fab")
		)
		(fp_line
			(start -0.12065 -0.305054)
			(end -0.12065 -0.2794)
			(stroke
				(width 0.1)
				(type default)
			)
			(layer "F.Fab")
		)
		(fp_line
			(start -0.67945 0.3048)
			(end -0.67945 -0.305054)
			(stroke
				(width 0.1)
				(type default)
			)
			(layer "F.Fab")
		)
		(fp_line
			(start -0.67945 -0.305054)
			(end -0.12065 -0.305054)
			(stroke
				(width 0.1)
				(type default)
			)
			(layer "F.Fab")
		)
		(pad "1" smd circle
			(at -0.40005 0 180)
			(size 0 0)
			(layers "F.Cu" "F.Mask" "F.Paste")
			(net "P1V8_RETIMER_CPU0_EN")
		)
		(pad "2" smd circle
			(at 0.40005 0 180)
			(size 0 0)
			(layers "F.Cu" "F.Mask" "F.Paste")
			(net "GND")
		)
	)
	(footprint ""
		(layer "F.Cu")
		(at 213.106 -98.425 90)
		(property "Reference" "R9030"
			(at 0 0 90)
			(layer "F.SilkS")
			(hide yes)
			(effects
				(font
					(size 1.27 1.27)
				)
			)
		)
		(property "Value" ""
			(at 0 0 90)
			(layer "F.Fab")
			(effects
				(font
					(size 1.27 1.27)
				)
			)
		)
		(duplicate_pad_numbers_are_jumpers no)
		(fp_line
			(start 0.7874 -0.4064)
			(end 0.7874 0.4064)
			(stroke
				(width 0.1524)
				(type default)
			)
			(layer "F.SilkS")
		)
		(fp_line
			(start -0.7874 -0.4064)
			(end 0.7874 -0.4064)
			(stroke
				(width 0.1524)
				(type default)
			)
			(layer "F.SilkS")
		)
		(fp_line
			(start 0.7874 0.4064)
			(end -0.7874 0.4064)
			(stroke
				(width 0.1524)
				(type default)
			)
			(layer "F.SilkS")
		)
		(fp_line
			(start -0.7874 0.4064)
			(end -0.7874 -0.4064)
			(stroke
				(width 0.1524)
				(type default)
			)
			(layer "F.SilkS")
		)
		(fp_line
			(start -0.12065 -0.305054)
			(end -0.12065 -0.2794)
			(stroke
				(width 0.1)
				(type default)
			)
			(layer "F.Fab")
		)
		(fp_line
			(start -0.67945 -0.305054)
			(end -0.12065 -0.305054)
			(stroke
				(width 0.1)
				(type default)
			)
			(layer "F.Fab")
		)
		(fp_line
			(start 0.67945 -0.3048)
			(end 0.67945 0.3048)
			(stroke
				(width 0.1)
				(type default)
			)
			(layer "F.Fab")
		)
		(fp_line
			(start 0.12065 -0.3048)
			(end 0.67945 -0.3048)
			(stroke
				(width 0.1)
				(type default)
			)
			(layer "F.Fab")
		)
		(fp_line
			(start 0.12065 -0.2794)
			(end 0.12065 -0.3048)
			(stroke
				(width 0.1)
				(type default)
			)
			(layer "F.Fab")
		)
		(fp_line
			(start -0.12065 -0.2794)
			(end 0.12065 -0.2794)
			(stroke
				(width 0.1)
				(type default)
			)
			(layer "F.Fab")
		)
		(fp_line
			(start 0.120396 0.2794)
			(end -0.12065 0.2794)
			(stroke
				(width 0.1)
				(type default)
			)
			(layer "F.Fab")
		)
		(fp_line
			(start -0.12065 0.2794)
			(end -0.12065 0.3048)
			(stroke
				(width 0.1)
				(type default)
			)
			(layer "F.Fab")
		)
		(fp_line
			(start 0.67945 0.3048)
			(end 0.120396 0.3048)
			(stroke
				(width 0.1)
				(type default)
			)
			(layer "F.Fab")
		)
		(fp_line
			(start 0.120396 0.3048)
			(end 0.120396 0.2794)
			(stroke
				(width 0.1)
				(type default)
			)
			(layer "F.Fab")
		)
		(fp_line
			(start -0.12065 0.3048)
			(end -0.67945 0.3048)
			(stroke
				(width 0.1)
				(type default)
			)
			(layer "F.Fab")
		)
		(fp_line
			(start -0.67945 0.3048)
			(end -0.67945 -0.305054)
			(stroke
				(width 0.1)
				(type default)
			)
			(layer "F.Fab")
		)
		(pad "1" smd circle
			(at -0.40005 0 90)
			(size 0 0)
			(layers "F.Cu" "F.Mask" "F.Paste")
			(net "OCP_SFF_AUX_PWR_EN_R3")
		)
		(pad "2" smd circle
			(at 0.40005 0 90)
			(size 0 0)
			(layers "F.Cu" "F.Mask" "F.Paste")
			(net "FM_PLD_OCP_SFF_AUX_PWR_EN")
		)
	)
)
